# S9S_MB_2U (Grand Teton) — schematic netlist excerpt (pin names and nets, part order shuffled) for the footprints in the layout excerpt that follows; sources: Cadence DE-HDL packaged netlist, KiCad conversion of 03242023_DA0F0TMBIJ0_F0T_Motherboard_J_brd_V01_OCP.brd

PC527_P1_4  Q_CAP  3300PF 50V 10% X7R  pkg 0402  page 286 : A = SW_P12V_PVCCIN_CPU1_FLT ; B = GND
R3497  Q_RES  33.2 1% CHIP  pkg 0402LF  page 150 : A = GPU_FPGA_EROT_RECOV_BUF_R_N ; B = GPU_FPGA_EROT_RECOV_BUF_N
C1579  Q_CAP_DIFFBUS  DIFF BUS_0.22UF 6.3V 20% X6S  pkg C0201  page 175 : \1\ = P5E_CPU0_PE4_TX_C_DP<0> ; \2\ = P5E_CPU0_PE4_TX_DP<0>

(kicad_pcb
	(version 20260206)
	(generator "pcbnew")
	(generator_version "10.0")
	(general
		(thickness 1.6)
		(legacy_teardrops no)
	)
	(paper "A4")
	(title_block
		(title "03242023_DA0F0TMBIJ0_F0T_Motherboard_J_brd_V01_OCP.brd")
		(comment 1 "Grand Teton / footprints 3876-3878 of 6105")
	)
	(layers
		(0 "F.Cu" signal "TOP")
		(4 "In1.Cu" signal "GND")
		(6 "In2.Cu" signal "IN1")
		(8 "In3.Cu" signal "GND1")
		(10 "In4.Cu" signal "IN2")
		(12 "In5.Cu" signal "GND2")
		(14 "In6.Cu" signal "IN3")
		(16 "In7.Cu" signal "GND3")
		(18 "In8.Cu" signal "VCC")
		(20 "In9.Cu" signal "VCC1")
		(22 "In10.Cu" signal "GND4")
		(24 "In11.Cu" signal "IN4")
		(26 "In12.Cu" signal "GND5")
		(28 "In13.Cu" signal "IN5")
		(30 "In14.Cu" signal "GND6")
		(32 "In15.Cu" signal "IN6")
		(34 "In16.Cu" signal "GND7")
		(2 "B.Cu" signal "BOTTOM")
		(9 "F.Adhes" user "F.Adhesive")
		(11 "B.Adhes" user "B.Adhesive")
		(13 "F.Paste" user "Package Geometry/Pastemask Top")
		(15 "B.Paste" user "Package Geometry/Pastemask Bottom")
		(5 "F.SilkS" user "Ref Des/Silkscreen Top")
		(7 "B.SilkS" user "Ref Des/Silkscreen Bottom")
		(1 "F.Mask" user "Board Geometry/Soldermask Top")
		(3 "B.Mask" user "Board Geometry/Soldermask Bottom")
		(17 "Dwgs.User" user "User.Drawings")
		(19 "Cmts.User" user "User.Comments")
		(21 "Eco1.User" user "User.Eco1")
		(23 "Eco2.User" user "User.Eco2")
		(25 "Edge.Cuts" user "Board Geometry/Outline")
		(27 "Margin" user)
		(31 "F.CrtYd" user "Package Geometry/Place Bound Top")
		(29 "B.CrtYd" user "Package Geometry/Place Bound Bottom")
		(35 "F.Fab" user "Ref Des/Assembly Top")
		(33 "B.Fab" user "Ref Des/Assembly Bottom")
	)
	(footprint ""
		(layer "F.Cu")
		(at 125.53696 -335.176368)
		(property "Reference" "PC527_P1_4"
			(at 0 0 0)
			(layer "F.SilkS")
			(hide yes)
			(effects
				(font
					(size 1.27 1.27)
				)
			)
		)
		(property "Value" ""
			(at 0 0 0)
			(layer "F.Fab")
			(effects
				(font
					(size 1.27 1.27)
				)
			)
		)
		(duplicate_pad_numbers_are_jumpers no)
		(fp_line
			(start -0.7874 -0.4064)
			(end 0.7874 -0.4064)
			(stroke
				(width 0.1524)
				(type default)
			)
			(layer "F.SilkS")
		)
		(fp_line
			(start -0.7874 0.4064)
			(end -0.7874 -0.4064)
			(stroke
				(width 0.1524)
				(type default)
			)
			(layer "F.SilkS")
		)
		(fp_line
			(start 0.7874 -0.4064)
			(end 0.7874 0.4064)
			(stroke
				(width 0.1524)
				(type default)
			)
			(layer "F.SilkS")
		)
		(fp_line
			(start 0.7874 0.4064)
			(end -0.7874 0.4064)
			(stroke
				(width 0.1524)
				(type default)
			)
			(layer "F.SilkS")
		)
		(fp_line
			(start -0.67945 -0.305054)
			(end -0.12065 -0.305054)
			(stroke
				(width 0.1)
				(type default)
			)
			(layer "F.Fab")
		)
		(fp_line
			(start -0.67945 0.3048)
			(end -0.67945 -0.305054)
			(stroke
				(width 0.1)
				(type default)
			)
			(layer "F.Fab")
		)
		(fp_line
			(start -0.12065 -0.305054)
			(end -0.12065 -0.2794)
			(stroke
				(width 0.1)
				(type default)
			)
			(layer "F.Fab")
		)
		(fp_line
			(start -0.12065 -0.2794)
			(end 0.12065 -0.2794)
			(stroke
				(width 0.1)
				(type default)
			)
			(layer "F.Fab")
		)
		(fp_line
			(start -0.12065 0.2794)
			(end -0.12065 0.3048)
			(stroke
				(width 0.1)
				(type default)
			)
			(layer "F.Fab")
		)
		(fp_line
			(start -0.12065 0.3048)
			(end -0.67945 0.3048)
			(stroke
				(width 0.1)
				(type default)
			)
			(layer "F.Fab")
		)
		(fp_line
			(start 0.120396 0.2794)
			(end -0.12065 0.2794)
			(stroke
				(width 0.1)
				(type default)
			)
			(layer "F.Fab")
		)
		(fp_line
			(start 0.120396 0.3048)
			(end 0.120396 0.2794)
			(stroke
				(width 0.1)
				(type default)
			)
			(layer "F.Fab")
		)
		(fp_line
			(start 0.12065 -0.3048)
			(end 0.67945 -0.3048)
			(stroke
				(width 0.1)
				(type default)
			)
			(layer "F.Fab")
		)
		(fp_line
			(start 0.12065 -0.2794)
			(end 0.12065 -0.3048)
			(stroke
				(width 0.1)
				(type default)
			)
			(layer "F.Fab")
		)
		(fp_line
			(start 0.67945 -0.3048)
			(end 0.67945 0.3048)
			(stroke
				(width 0.1)
				(type default)
			)
			(layer "F.Fab")
		)
		(fp_line
			(start 0.67945 0.3048)
			(end 0.120396 0.3048)
			(stroke
				(width 0.1)
				(type default)
			)
			(layer "F.Fab")
		)
		(pad "1" smd circle
			(at -0.40005 0)
			(size 0 0)
			(layers "F.Cu" "F.Mask" "F.Paste")
			(net "SW_P12V_PVCCIN_CPU1_FLT")
		)
		(pad "2" smd circle
			(at 0.40005 0)
			(size 0 0)
			(layers "F.Cu" "F.Mask" "F.Paste")
			(net "GND")
		)
	)
	(footprint ""
		(layer "F.Cu")
		(at 304.869088 -402.371052 -90)
		(property "Reference" "C1579"
			(at 0 0 270)
			(layer "F.SilkS")
			(hide yes)
			(effects
				(font
					(size 1.27 1.27)
				)
			)
		)
		(property "Value" ""
			(at 0 0 270)
			(layer "F.Fab")
			(effects
				(font
					(size 1.27 1.27)
				)
			)
		)
		(duplicate_pad_numbers_are_jumpers no)
		(fp_line
			(start -0.299974 0.150114)
			(end -0.299974 -0.150114)
			(stroke
				(width 0.1)
				(type default)
			)
			(layer "F.Fab")
		)
		(fp_line
			(start 0.299974 0.150114)
			(end -0.299974 0.150114)
			(stroke
				(width 0.1)
				(type default)
			)
			(layer "F.Fab")
		)
		(fp_line
			(start -0.299974 -0.150114)
			(end 0.299974 -0.150114)
			(stroke
				(width 0.1)
				(type default)
			)
			(layer "F.Fab")
		)
		(fp_line
			(start 0.299974 -0.150114)
			(end 0.299974 0.150114)
			(stroke
				(width 0.1)
				(type default)
			)
			(layer "F.Fab")
		)
		(pad "1" smd rect
			(at -0.2667 0 270)
			(size 0.3048 0.381)
			(layers "F.Cu" "F.Mask" "F.Paste")
			(net "P5E_CPU0_PE4_TX_C_DP<0>")
		)
		(pad "2" smd rect
			(at 0.2667 0 270)
			(size 0.3048 0.381)
			(layers "F.Cu" "F.Mask" "F.Paste")
			(net "P5E_CPU0_PE4_TX_DP<0>")
		)
	)
	(footprint ""
		(layer "F.Cu")
		(at 109.063282 -406.058116 90)
		(property "Reference" "R3497"
			(at 0 0 90)
			(layer "F.SilkS")
			(hide yes)
			(effects
				(font
					(size 1.27 1.27)
				)
			)
		)
		(property "Value" ""
			(at 0 0 90)
			(layer "F.Fab")
			(effects
				(font
					(size 1.27 1.27)
				)
			)
		)
		(duplicate_pad_numbers_are_jumpers no)
		(fp_line
			(start 0.7874 -0.4064)
			(end 0.7874 0.4064)
			(stroke
				(width 0.1524)
				(type default)
			)
			(layer "F.SilkS")
		)
		(fp_line
			(start -0.7874 -0.4064)
			(end 0.7874 -0.4064)
			(stroke
				(width 0.1524)
				(type default)
			)
			(layer "F.SilkS")
		)
		(fp_line
			(start 0.7874 0.4064)
			(end -0.7874 0.4064)
			(stroke
				(width 0.1524)
				(type default)
			)
			(layer "F.SilkS")
		)
		(fp_line
			(start -0.7874 0.4064)
			(end -0.7874 -0.4064)
			(stroke
				(width 0.1524)
				(type default)
			)
			(layer "F.SilkS")
		)
		(fp_line
			(start -0.12065 -0.305054)
			(end -0.12065 -0.2794)
			(stroke
				(width 0.1)
				(type default)
			)
			(layer "F.Fab")
		)
		(fp_line
			(start -0.67945 -0.305054)
			(end -0.12065 -0.305054)
			(stroke
				(width 0.1)
				(type default)
			)
			(layer "F.Fab")
		)
		(fp_line
			(start 0.67945 -0.3048)
			(end 0.67945 0.3048)
			(stroke
				(width 0.1)
				(type default)
			)
			(layer "F.Fab")
		)
		(fp_line
			(start 0.12065 -0.3048)
			(end 0.67945 -0.3048)
			(stroke
				(width 0.1)
				(type default)
			)
			(layer "F.Fab")
		)
		(fp_line
			(start 0.12065 -0.2794)
			(end 0.12065 -0.3048)
			(stroke
				(width 0.1)
				(type default)
			)
			(layer "F.Fab")
		)
		(fp_line
			(start -0.12065 -0.2794)
			(end 0.12065 -0.2794)
			(stroke
				(width 0.1)
				(type default)
			)
			(layer "F.Fab")
		)
		(fp_line
			(start 0.120396 0.2794)
			(end -0.12065 0.2794)
			(stroke
				(width 0.1)
				(type default)
			)
			(layer "F.Fab")
		)
		(fp_line
			(start -0.12065 0.2794)
			(end -0.12065 0.3048)
			(stroke
				(width 0.1)
				(type default)
			)
			(layer "F.Fab")
		)
		(fp_line
			(start 0.67945 0.3048)
			(end 0.120396 0.3048)
			(stroke
				(width 0.1)
				(type default)
			)
			(layer "F.Fab")
		)
		(fp_line
			(start 0.120396 0.3048)
			(end 0.120396 0.2794)
			(stroke
				(width 0.1)
				(type default)
			)
			(layer "F.Fab")
		)
		(fp_line
			(start -0.12065 0.3048)
			(end -0.67945 0.3048)
			(stroke
				(width 0.1)
				(type default)
			)
			(layer "F.Fab")
		)
		(fp_line
			(start -0.67945 0.3048)
			(end -0.67945 -0.305054)
			(stroke
				(width 0.1)
				(type default)
			)
			(layer "F.Fab")
		)
		(pad "1" smd circle
			(at -0.40005 0 90)
			(size 0 0)
			(layers "F.Cu" "F.Mask" "F.Paste")
			(net "GPU_FPGA_EROT_RECOV_BUF_R_N")
		)
		(pad "2" smd circle
			(at 0.40005 0 90)
			(size 0 0)
			(layers "F.Cu" "F.Mask" "F.Paste")
			(net "GPU_FPGA_EROT_RECOV_BUF_N")
		)
	)
)
